(kicad_pcb
	(version 20260206)
	(generator "pcbnew")
	(generator_version "10.0")
	(general
		(thickness 1.6)
		(legacy_teardrops no)
	)
	(paper "A4")
	(title_block
		(title "v1-chassis-manager — T6M_CM_d_v01_1031_1645.brd")
		(comment 1 "Open CloudServer (Microsoft) / footprints 160-166 of 2512")
	)
	(layers
		(0 "F.Cu" signal "TOP")
		(4 "In1.Cu" signal "GND1")
		(6 "In2.Cu" signal "IN1")
		(8 "In3.Cu" signal "VCC1")
		(10 "In4.Cu" signal "VCC2")
		(12 "In5.Cu" signal "GND2")
		(14 "In6.Cu" signal "IN2")
		(16 "In7.Cu" signal "IN3")
		(18 "In8.Cu" signal "GND3")
		(2 "B.Cu" signal "BOTTOM")
		(9 "F.Adhes" user "F.Adhesive")
		(11 "B.Adhes" user "B.Adhesive")
		(13 "F.Paste" user "Package Geometry/Pastemask Top")
		(15 "B.Paste" user "Package Geometry/Pastemask Bottom")
		(5 "F.SilkS" user "Ref Des/Silkscreen Top")
		(7 "B.SilkS" user "Ref Des/Silkscreen Bottom")
		(1 "F.Mask" user "Board Geometry/Soldermask Top")
		(3 "B.Mask" user "Board Geometry/Soldermask Bottom")
		(17 "Dwgs.User" user "User.Drawings")
		(19 "Cmts.User" user "User.Comments")
		(21 "Eco1.User" user "User.Eco1")
		(23 "Eco2.User" user "User.Eco2")
		(25 "Edge.Cuts" user "Board Geometry/Outline")
		(27 "Margin" user)
		(31 "F.CrtYd" user "Package Geometry/Place Bound Top")
		(29 "B.CrtYd" user "Package Geometry/Place Bound Bottom")
		(35 "F.Fab" user "Ref Des/Assembly Top")
		(33 "B.Fab" user "Ref Des/Assembly Bottom")
	)
	(footprint ""
		(layer "F.Cu")
		(at 114.849656 -106.35107 90)
		(property "Reference" "PC100"
			(at -0.745236 4.893564 0)
			(unlocked yes)
			(layer "F.SilkS")
			(effects
				(font
					(size 0.7874 0.5842)
					(thickness 0.1524)
				)
				(justify left)
			)
		)
		(property "Value" ""
			(at 0 0 90)
			(layer "F.Fab")
			(effects
				(font
					(size 1.27 1.27)
				)
			)
		)
		(duplicate_pad_numbers_are_jumpers no)
		(fp_line
			(start 2.249932 -4.533392)
			(end 2.249932 4.533392)
			(stroke
				(width 0.1524)
				(type default)
			)
			(layer "F.SilkS")
		)
		(fp_line
			(start -2.249932 -4.533392)
			(end 2.249932 -4.533392)
			(stroke
				(width 0.1524)
				(type default)
			)
			(layer "F.SilkS")
		)
		(fp_line
			(start 2.249932 4.533392)
			(end -2.249932 4.533392)
			(stroke
				(width 0.1524)
				(type default)
			)
			(layer "F.SilkS")
		)
		(fp_line
			(start -2.249932 4.533392)
			(end -2.249932 -4.533392)
			(stroke
				(width 0.1524)
				(type default)
			)
			(layer "F.SilkS")
		)
		(fp_poly
			(pts
				(xy 2.326132 -4.533392) (xy 2.326132 -5.39242) (xy -2.326132 -5.39242) (xy -2.326132 -4.533392)
			)
			(stroke
				(width 0)
				(type default)
			)
			(fill yes)
			(layer "F.SilkS")
		)
		(fp_poly
			(pts
				(xy -1.4605 4.457192) (xy -1.4605 3.750056) (xy -2.249932 3.750056) (xy -2.249932 -3.750056) (xy -1.4605 -3.750056)
				(xy -1.4605 -4.457192) (xy 1.4605 -4.457192) (xy 1.4605 -3.750056) (xy 2.249932 -3.750056) (xy 2.249932 3.750056)
				(xy 1.4605 3.750056) (xy 1.4605 4.457192)
			)
			(stroke
				(width 0)
				(type default)
			)
			(fill no)
			(layer "F.CrtYd")
		)
		(fp_line
			(start 2.249932 -3.750056)
			(end 2.249932 3.750056)
			(stroke
				(width 0.1)
				(type default)
			)
			(layer "F.Fab")
		)
		(fp_line
			(start -2.249932 -3.750056)
			(end 2.249932 -3.750056)
			(stroke
				(width 0.1)
				(type default)
			)
			(layer "F.Fab")
		)
		(fp_line
			(start 2.249932 3.750056)
			(end -2.249932 3.750056)
			(stroke
				(width 0.1)
				(type default)
			)
			(layer "F.Fab")
		)
		(fp_line
			(start -2.249932 3.750056)
			(end -2.249932 -3.750056)
			(stroke
				(width 0.1)
				(type default)
			)
			(layer "F.Fab")
		)
		(fp_text user "+"
			(at 0.4191 -5.642356 180)
			(unlocked yes)
			(layer "F.SilkS")
			(effects
				(font
					(size 1.6002 1.1938)
					(thickness 0.1524)
				)
				(justify left)
			)
		)
		(fp_text user "+"
			(at -0.786384 -6.322314 90)
			(unlocked yes)
			(layer "F.Fab")
			(effects
				(font
					(size 1.905 1.4224)
					(thickness 0.000001)
				)
				(justify left)
			)
		)
		(pad "1" smd rect
			(at 0 -3.199892)
			(size 2.413 2.8194)
			(layers "F.Cu" "F.Mask" "F.Paste")
			(net "PV_VCCP_NODE1")
		)
		(pad "2" smd rect
			(at 0 3.199892)
			(size 2.413 2.8194)
			(layers "F.Cu" "F.Mask" "F.Paste")
			(net "GND")
		)
	)
	(footprint ""
		(layer "F.Cu")
		(at 67.265296 -101.4603 180)
		(property "Reference" "Q30"
			(at 0.534416 2.946908 0)
			(unlocked yes)
			(layer "F.SilkS")
			(effects
				(font
					(size 0.7874 0.5842)
					(thickness 0.1524)
				)
			)
		)
		(property "Value" ""
			(at 0 0 180)
			(layer "F.Fab")
			(effects
				(font
					(size 1.27 1.27)
				)
			)
		)
		(duplicate_pad_numbers_are_jumpers no)
		(fp_line
			(start 1.603248 1.500124)
			(end -1.603248 1.500124)
			(stroke
				(width 0.1524)
				(type default)
			)
			(layer "F.SilkS")
		)
		(fp_line
			(start 1.603248 -1.500124)
			(end 1.603248 1.500124)
			(stroke
				(width 0.1524)
				(type default)
			)
			(layer "F.SilkS")
		)
		(fp_line
			(start -1.603248 1.500124)
			(end -1.603248 -1.500124)
			(stroke
				(width 0.1524)
				(type default)
			)
			(layer "F.SilkS")
		)
		(fp_line
			(start -1.603248 -1.500124)
			(end 1.603248 -1.500124)
			(stroke
				(width 0.1524)
				(type default)
			)
			(layer "F.SilkS")
		)
		(fp_poly
			(pts
				(xy -0.700024 -1.500124) (xy -0.700024 -1.40716) (xy -1.507998 -1.40716) (xy -1.507998 -0.49276)
				(xy -0.700024 -0.49276) (xy -0.700024 0.47244) (xy -1.507998 0.47244) (xy -1.507998 1.41224) (xy -0.700024 1.41224)
				(xy -0.700024 1.500124) (xy 0.700024 1.500124) (xy 0.700024 0.47244) (xy 1.514602 0.47244) (xy 1.514602 -0.46736)
				(xy 0.700024 -0.46736) (xy 0.700024 -1.500124)
			)
			(stroke
				(width 0)
				(type default)
			)
			(fill no)
			(layer "F.CrtYd")
		)
		(fp_line
			(start 0.700024 1.500124)
			(end -0.700024 1.500124)
			(stroke
				(width 0.1)
				(type default)
			)
			(layer "F.Fab")
		)
		(fp_line
			(start 0.700024 -1.500124)
			(end 0.700024 1.500124)
			(stroke
				(width 0.1)
				(type default)
			)
			(layer "F.Fab")
		)
		(fp_line
			(start -0.700024 1.500124)
			(end -0.700024 -1.500124)
			(stroke
				(width 0.1)
				(type default)
			)
			(layer "F.Fab")
		)
		(fp_line
			(start -0.700024 -1.500124)
			(end 0.700024 -1.500124)
			(stroke
				(width 0.1)
				(type default)
			)
			(layer "F.Fab")
		)
		(fp_text user "D"
			(at 2.06375 1.879854 0)
			(unlocked yes)
			(layer "F.SilkS")
			(effects
				(font
					(size 0.635 0.4064)
					(thickness 0.1524)
				)
			)
		)
		(fp_text user "S"
			(at -1.146556 2.002282 0)
			(unlocked yes)
			(layer "F.SilkS")
			(effects
				(font
					(size 0.635 0.4064)
					(thickness 0.1524)
				)
			)
		)
		(fp_text user "G"
			(at -1.252982 -2.044954 0)
			(unlocked yes)
			(layer "F.SilkS")
			(effects
				(font
					(size 0.635 0.4064)
					(thickness 0.1524)
				)
			)
		)
		(fp_text user "D"
			(at 2.098294 0.1016 90)
			(unlocked yes)
			(layer "F.Fab")
			(effects
				(font
					(size 0.7874 0.5842)
					(thickness 0.000001)
				)
			)
		)
		(fp_text user "S"
			(at -1.025906 2.0066 90)
			(unlocked yes)
			(layer "F.Fab")
			(effects
				(font
					(size 0.7874 0.5842)
					(thickness 0.000001)
				)
			)
		)
		(fp_text user "G"
			(at -1.051306 -2.032 90)
			(unlocked yes)
			(layer "F.Fab")
			(effects
				(font
					(size 0.7874 0.5842)
					(thickness 0.000001)
				)
			)
		)
		(pad "D" smd rect
			(at 0.999998 0 90)
			(size 0.8128 0.9144)
			(layers "F.Cu" "F.Mask" "F.Paste")
			(net "FM_CPLD_NODE1_P1V8_SUS_EN_LV")
		)
		(pad "G" smd rect
			(at -0.999998 -0.94996 90)
			(size 0.8128 0.9144)
			(layers "F.Cu" "F.Mask" "F.Paste")
			(net "FM_CPLD_NODE1_P1V8_SUS_EN_G")
		)
		(pad "S" smd rect
			(at -0.999998 0.94996 90)
			(size 0.8128 0.9144)
			(layers "F.Cu" "F.Mask" "F.Paste")
			(net "FM_CPLD_NODE1_P1V8_SUS_EN")
		)
	)
	(footprint ""
		(layer "F.Cu")
		(at 128.05156 -188.126624 90)
		(property "Reference" "C740"
			(at 4.951476 -0.496316 90)
			(unlocked yes)
			(layer "F.SilkS")
			(effects
				(font
					(size 0.7874 0.5842)
					(thickness 0.1524)
				)
				(justify left)
			)
		)
		(property "Value" ""
			(at 0 0 90)
			(layer "F.Fab")
			(effects
				(font
					(size 1.27 1.27)
				)
			)
		)
		(duplicate_pad_numbers_are_jumpers no)
		(fp_line
			(start 0.7874 -0.4064)
			(end 0.7874 0.4064)
			(stroke
				(width 0.1524)
				(type default)
			)
			(layer "F.SilkS")
		)
		(fp_line
			(start -0.7874 -0.4064)
			(end 0.7874 -0.4064)
			(stroke
				(width 0.1524)
				(type default)
			)
			(layer "F.SilkS")
		)
		(fp_line
			(start 0 0.381)
			(end 0 -0.381)
			(stroke
				(width 0.1524)
				(type default)
			)
			(layer "F.SilkS")
		)
		(fp_line
			(start 0.7874 0.4064)
			(end -0.7874 0.4064)
			(stroke
				(width 0.1524)
				(type default)
			)
			(layer "F.SilkS")
		)
		(fp_line
			(start -0.7874 0.4064)
			(end -0.7874 -0.4064)
			(stroke
				(width 0.1524)
				(type default)
			)
			(layer "F.SilkS")
		)
		(fp_poly
			(pts
				(xy -0.5334 0.254) (xy -0.635 0.254) (xy -0.635 0.2286) (xy -0.635 -0.254) (xy -0.5334 -0.254) (xy -0.5334 -0.2794)
				(xy 0.5334 -0.2794) (xy 0.5334 -0.254) (xy 0.635 -0.254) (xy 0.635 0.254) (xy 0.5334 0.254) (xy 0.5334 0.2794)
				(xy -0.508 0.2794) (xy -0.5334 0.2794)
			)
			(stroke
				(width 0)
				(type default)
			)
			(fill no)
			(layer "F.CrtYd")
		)
		(pad "1" smd rect
			(at 0.40005 0 90)
			(size 0.4572 0.508)
			(layers "F.Cu" "F.Mask" "F.Paste")
			(net "UART_T9_NODE4_TXD_R")
		)
		(pad "2" smd rect
			(at -0.40005 0 90)
			(size 0.4572 0.508)
			(layers "F.Cu" "F.Mask" "F.Paste")
			(net "GND")
		)
	)
	(footprint ""
		(layer "F.Cu")
		(at 162.17138 -161.37001 90)
		(property "Reference" "R586"
			(at -8.06577 17.640554 90)
			(unlocked yes)
			(layer "F.SilkS")
			(effects
				(font
					(size 0.7874 0.5842)
					(thickness 0.1524)
				)
				(justify left)
			)
		)
		(property "Value" ""
			(at 0 0 90)
			(layer "F.Fab")
			(effects
				(font
					(size 1.27 1.27)
				)
			)
		)
		(duplicate_pad_numbers_are_jumpers no)
		(fp_line
			(start 0.7874 -0.4064)
			(end 0.7874 0.4064)
			(stroke
				(width 0.1524)
				(type default)
			)
			(layer "F.SilkS")
		)
		(fp_line
			(start -0.7874 -0.4064)
			(end 0.7874 -0.4064)
			(stroke
				(width 0.1524)
				(type default)
			)
			(layer "F.SilkS")
		)
		(fp_line
			(start 0.7874 0.4064)
			(end -0.7874 0.4064)
			(stroke
				(width 0.1524)
				(type default)
			)
			(layer "F.SilkS")
		)
		(fp_line
			(start -0.7874 0.4064)
			(end -0.7874 -0.4064)
			(stroke
				(width 0.1524)
				(type default)
			)
			(layer "F.SilkS")
		)
		(fp_poly
			(pts
				(xy -0.508 0.2794) (xy -0.508 0.2286) (xy -0.635 0.2286) (xy -0.635 -0.254) (xy -0.5334 -0.254)
				(xy -0.5334 -0.2794) (xy 0.5334 -0.2794) (xy 0.5334 -0.254) (xy 0.635 -0.254) (xy 0.635 0.254) (xy 0.5334 0.254)
				(xy 0.5334 0.2794)
			)
			(stroke
				(width 0)
				(type default)
			)
			(fill no)
			(layer "F.CrtYd")
		)
		(pad "1" smd rect
			(at 0.40005 0 90)
			(size 0.4572 0.508)
			(layers "F.Cu" "F.Mask" "F.Paste")
			(net "GND")
		)
		(pad "2" smd rect
			(at -0.40005 0 90)
			(size 0.4572 0.508)
			(layers "F.Cu" "F.Mask" "F.Paste")
			(net "LAN2_NC_SI_TX_EN")
		)
	)
	(footprint ""
		(layer "F.Cu")
		(at 16.499332 -133.709918 180)
		(property "Reference" "PC65"
			(at 0.841248 2.093468 0)
			(unlocked yes)
			(layer "F.SilkS")
			(effects
				(font
					(size 0.7874 0.5842)
					(thickness 0.1524)
				)
				(justify left)
			)
		)
		(property "Value" ""
			(at 0 0 180)
			(layer "F.Fab")
			(effects
				(font
					(size 1.27 1.27)
				)
			)
		)
		(duplicate_pad_numbers_are_jumpers no)
		(fp_line
			(start 0.7874 0.4064)
			(end -0.7874 0.4064)
			(stroke
				(width 0.1524)
				(type default)
			)
			(layer "F.SilkS")
		)
		(fp_line
			(start 0.7874 -0.4064)
			(end 0.7874 0.4064)
			(stroke
				(width 0.1524)
				(type default)
			)
			(layer "F.SilkS")
		)
		(fp_line
			(start 0 0.381)
			(end 0 -0.381)
			(stroke
				(width 0.1524)
				(type default)
			)
			(layer "F.SilkS")
		)
		(fp_line
			(start -0.7874 0.4064)
			(end -0.7874 -0.4064)
			(stroke
				(width 0.1524)
				(type default)
			)
			(layer "F.SilkS")
		)
		(fp_line
			(start -0.7874 -0.4064)
			(end 0.7874 -0.4064)
			(stroke
				(width 0.1524)
				(type default)
			)
			(layer "F.SilkS")
		)
		(fp_poly
			(pts
				(xy -0.5334 0.254) (xy -0.635 0.254) (xy -0.635 0.2286) (xy -0.635 -0.254) (xy -0.5334 -0.254) (xy -0.5334 -0.2794)
				(xy 0.5334 -0.2794) (xy 0.5334 -0.254) (xy 0.635 -0.254) (xy 0.635 0.254) (xy 0.5334 0.254) (xy 0.5334 0.2794)
				(xy -0.508 0.2794) (xy -0.5334 0.2794)
			)
			(stroke
				(width 0)
				(type default)
			)
			(fill no)
			(layer "F.CrtYd")
		)
		(pad "1" smd rect
			(at 0.40005 0 180)
			(size 0.4572 0.508)
			(layers "F.Cu" "F.Mask" "F.Paste")
			(net "VSENSE_P1V05_NODE1_N")
		)
		(pad "2" smd rect
			(at -0.40005 0 180)
			(size 0.4572 0.508)
			(layers "F.Cu" "F.Mask" "F.Paste")
			(net "P1V05_NODE1_VREF")
		)
	)
	(footprint ""
		(layer "F.Cu")
		(at 147.433792 -144.082262)
		(property "Reference" "R275"
			(at -1.293876 1.072642 0)
			(unlocked yes)
			(layer "F.SilkS")
			(effects
				(font
					(size 0.635 0.4064)
					(thickness 0.1524)
				)
				(justify left)
			)
		)
		(property "Value" ""
			(at 0 0 0)
			(layer "F.Fab")
			(effects
				(font
					(size 1.27 1.27)
				)
			)
		)
		(duplicate_pad_numbers_are_jumpers no)
		(fp_line
			(start -0.7874 -0.4064)
			(end 0.7874 -0.4064)
			(stroke
				(width 0.1524)
				(type default)
			)
			(layer "F.SilkS")
		)
		(fp_line
			(start -0.7874 0.4064)
			(end -0.7874 -0.4064)
			(stroke
				(width 0.1524)
				(type default)
			)
			(layer "F.SilkS")
		)
		(fp_line
			(start 0.7874 -0.4064)
			(end 0.7874 0.4064)
			(stroke
				(width 0.1524)
				(type default)
			)
			(layer "F.SilkS")
		)
		(fp_line
			(start 0.7874 0.4064)
			(end -0.7874 0.4064)
			(stroke
				(width 0.1524)
				(type default)
			)
			(layer "F.SilkS")
		)
		(fp_poly
			(pts
				(xy -0.508 0.2794) (xy -0.508 0.2286) (xy -0.635 0.2286) (xy -0.635 -0.254) (xy -0.5334 -0.254)
				(xy -0.5334 -0.2794) (xy 0.5334 -0.2794) (xy 0.5334 -0.254) (xy 0.635 -0.254) (xy 0.635 0.254) (xy 0.5334 0.254)
				(xy 0.5334 0.2794)
			)
			(stroke
				(width 0)
				(type default)
			)
			(fill no)
			(layer "F.CrtYd")
		)
		(pad "1" smd rect
			(at 0.40005 0)
			(size 0.4572 0.508)
			(layers "F.Cu" "F.Mask" "F.Paste")
			(net "P3V3_NODE1")
		)
		(pad "2" smd rect
			(at -0.40005 0)
			(size 0.4572 0.508)
			(layers "F.Cu" "F.Mask" "F.Paste")
			(net "PCIE_SW_PWR_SAV")
		)
	)
	(footprint ""
		(layer "F.Cu")
		(at 100.471732 -171.879768 -90)
		(property "Reference" "U69"
			(at 72.6948 -87.253064 0)
			(unlocked yes)
			(layer "F.SilkS")
			(effects
				(font
					(size 0.7874 0.5842)
					(thickness 0.1524)
				)
			)
		)
		(property "Value" ""
			(at 0 0 270)
			(layer "F.Fab")
			(effects
				(font
					(size 1.27 1.27)
				)
			)
		)
		(duplicate_pad_numbers_are_jumpers no)
		(fp_line
			(start -2.4892 1.524)
			(end -2.4892 0.5588)
			(stroke
				(width 0.1524)
				(type default)
			)
			(layer "F.SilkS")
		)
		(fp_line
			(start 2.4892 1.524)
			(end -2.4892 1.524)
			(stroke
				(width 0.1524)
				(type default)
			)
			(layer "F.SilkS")
		)
		(fp_line
			(start -2.4892 0.5588)
			(end -1.9304 0)
			(stroke
				(width 0.1524)
				(type default)
			)
			(layer "F.SilkS")
		)
		(fp_line
			(start -1.9304 0)
			(end -2.4892 -0.5588)
			(stroke
				(width 0.1524)
				(type default)
			)
			(layer "F.SilkS")
		)
		(fp_line
			(start -2.4892 -0.5588)
			(end -2.4892 -1.524)
			(stroke
				(width 0.1524)
				(type default)
			)
			(layer "F.SilkS")
		)
		(fp_line
			(start -2.4892 -1.524)
			(end 2.4892 -1.524)
			(stroke
				(width 0.1524)
				(type default)
			)
			(layer "F.SilkS")
		)
		(fp_line
			(start 2.4892 -1.524)
			(end 2.4892 1.524)
			(stroke
				(width 0.1524)
				(type default)
			)
			(layer "F.SilkS")
		)
		(fp_circle
			(center -1.905 1.016)
			(end -1.905 0.762)
			(stroke
				(width 0.1524)
				(type default)
			)
			(fill no)
			(layer "F.SilkS")
		)
		(fp_poly
			(pts
				(xy -2.4003 3.5179) (xy -2.4003 2.0066) (xy -2.4892 2.0066) (xy -2.4892 -2.0066) (xy -2.4003 -2.0066)
				(xy -2.4003 -3.5179) (xy 2.4003 -3.5179) (xy 2.4003 -2.0066) (xy 2.4892 -2.0066) (xy 2.4892 2.0066)
				(xy 2.4003 2.0066) (xy 2.4003 3.5179)
			)
			(stroke
				(width 0)
				(type default)
			)
			(fill no)
			(layer "F.CrtYd")
		)
		(pad "1" smd rect
			(at -2.2225 2.7432 270)
			(size 0.3556 1.5494)
			(layers "F.Cu" "F.Mask" "F.Paste")
			(net "I2C_SCL_FANCTRL1_R")
		)
		(pad "2" smd rect
			(at -1.5875 2.7432 270)
			(size 0.3556 1.5494)
			(layers "F.Cu" "F.Mask" "F.Paste")
			(net "GND")
		)
		(pad "3" smd rect
			(at -0.9525 2.7432 270)
			(size 0.3556 1.5494)
			(layers "F.Cu" "F.Mask" "F.Paste")
			(net "P3V3_NODE1")
		)
		(pad "4" smd rect
			(at -0.3175 2.7432 270)
			(size 0.3556 1.5494)
			(layers "F.Cu" "F.Mask" "F.Paste")
			(net "FAN3_TACH_IN")
		)
		(pad "5" smd rect
			(at 0.3175 2.7432 270)
			(size 0.3556 1.5494)
			(layers "F.Cu" "F.Mask" "F.Paste")
			(net "Net_2256")
		)
		(pad "6" smd rect
			(at 0.9525 2.7432 270)
			(size 0.3556 1.5494)
			(layers "F.Cu" "F.Mask" "F.Paste")
			(net "FAN1_TACH_IN")
		)
		(pad "7" smd rect
			(at 1.5875 2.7432 270)
			(size 0.3556 1.5494)
			(layers "F.Cu" "F.Mask" "F.Paste")
			(net "FAN2_TACH_IN")
		)
		(pad "8" smd rect
			(at 2.2225 2.7432 270)
			(size 0.3556 1.5494)
			(layers "F.Cu" "F.Mask" "F.Paste")
			(net "Net_2255")
		)
		(pad "9" smd rect
			(at 2.2225 -2.7432 270)
			(size 0.3556 1.5494)
			(layers "F.Cu" "F.Mask" "F.Paste")
			(net "FAN4_TACH_IN")
		)
		(pad "10" smd rect
			(at 1.5875 -2.7432 270)
			(size 0.3556 1.5494)
			(layers "F.Cu" "F.Mask" "F.Paste")
			(net "Net_2254")
		)
		(pad "11" smd rect
			(at 0.9525 -2.7432 270)
			(size 0.3556 1.5494)
			(layers "F.Cu" "F.Mask" "F.Paste")
			(net "FNACTRL1_ADD")
		)
		(pad "12" smd rect
			(at 0.3175 -2.7432 270)
			(size 0.3556 1.5494)
			(layers "F.Cu" "F.Mask" "F.Paste")
			(net "FNACTRL1_TMP_IN")
		)
		(pad "13" smd rect
			(at -0.3175 -2.7432 270)
			(size 0.3556 1.5494)
			(layers "F.Cu" "F.Mask" "F.Paste")
			(net "CPLD_FAN_MAX_CTRL")
		)
		(pad "14" smd rect
			(at -0.9525 -2.7432 270)
			(size 0.3556 1.5494)
			(layers "F.Cu" "F.Mask" "F.Paste")
			(net "I2C_ALERT_FNACTRL1_N")
		)
		(pad "15" smd rect
			(at -1.5875 -2.7432 270)
			(size 0.3556 1.5494)
			(layers "F.Cu" "F.Mask" "F.Paste")
			(net "FAN_PWM_BUF")
		)
		(pad "16" smd rect
			(at -2.2225 -2.7432 270)
			(size 0.3556 1.5494)
			(layers "F.Cu" "F.Mask" "F.Paste")
			(net "I2C_SDA_FANCTRL1_R")
		)
	)
)
